(kicad_pcb
	(version 20260206)
	(generator "pcbnew")
	(generator_version "10.0")
	(general
		(thickness 1.6)
		(legacy_teardrops no)
	)
	(paper "A4")
	(title_block
		(title "peb — Lightning_PEB_BRD.brd")
		(comment 1 "Lightning (Wiwynn / Facebook NVMe JBOF) / footprints 1647-1651 of 2563")
	)
	(layers
		(0 "F.Cu" signal "TOP")
		(4 "In1.Cu" signal "L2GND")
		(6 "In2.Cu" signal "L3")
		(8 "In3.Cu" signal "L4VCC")
		(10 "In4.Cu" signal "L5VCC")
		(12 "In5.Cu" signal "L6")
		(14 "In6.Cu" signal "L7GND")
		(2 "B.Cu" signal "BOTTOM")
		(9 "F.Adhes" user "F.Adhesive")
		(11 "B.Adhes" user "B.Adhesive")
		(13 "F.Paste" user "Package Geometry/Pastemask Top")
		(15 "B.Paste" user "Package Geometry/Pastemask Bottom")
		(5 "F.SilkS" user "Ref Des/Silkscreen Top")
		(7 "B.SilkS" user "Ref Des/Silkscreen Bottom")
		(1 "F.Mask" user "Board Geometry/Soldermask Top")
		(3 "B.Mask" user "Board Geometry/Soldermask Bottom")
		(17 "Dwgs.User" user "User.Drawings")
		(19 "Cmts.User" user "User.Comments")
		(21 "Eco1.User" user "User.Eco1")
		(23 "Eco2.User" user "User.Eco2")
		(25 "Edge.Cuts" user "Board Geometry/Outline")
		(27 "Margin" user)
		(31 "F.CrtYd" user "Package Geometry/Place Bound Top")
		(29 "B.CrtYd" user "Package Geometry/Place Bound Bottom")
		(35 "F.Fab" user "Ref Des/Assembly Top")
		(33 "B.Fab" user "Ref Des/Assembly Bottom")
	)
	(footprint ""
		(layer "F.Cu")
		(at 146.2024 -41.3766 180)
		(property "Reference" "R767"
			(at 0 0 180)
			(layer "F.SilkS")
			(hide yes)
			(effects
				(font
					(size 1.27 1.27)
				)
			)
		)
		(property "Value" "4K7R2F-GP"
			(at 0.064008 -3.993896 180)
			(unlocked yes)
			(layer "F.Fab")
			(hide yes)
			(effects
				(font
					(size 1.016 1.016)
					(thickness 0.1524)
				)
			)
		)
		(property "Device Type" "R402H16"
			(at 0.064008 -5.517896 180)
			(unlocked yes)
			(layer "F.Fab")
			(hide yes)
			(effects
				(font
					(size 1.016 1.016)
					(thickness 0.1524)
				)
			)
		)
		(duplicate_pad_numbers_are_jumpers no)
		(fp_line
			(start 0.508 -0.9398)
			(end -0.508 -0.9398)
			(stroke
				(width 0.1524)
				(type default)
			)
			(layer "F.SilkS")
		)
		(fp_line
			(start -0.508 -0.9398)
			(end -0.508 0.9398)
			(stroke
				(width 0.1524)
				(type default)
			)
			(layer "F.SilkS")
		)
		(fp_rect
			(start -0.508 0.9398)
			(end 0.508 -0.9398)
			(stroke
				(width 0)
				(type default)
			)
			(fill no)
			(layer "F.CrtYd")
		)
		(fp_rect
			(start -0.508 0.9398)
			(end 0.508 -0.9398)
			(stroke
				(width 0)
				(type default)
			)
			(fill no)
			(layer "F.Fab")
		)
		(pad "1" smd custom
			(at 0 -0.4445 180)
			(size 0.1397 0.1397)
			(layers "F.Cu" "F.Mask" "F.Paste")
			(net "DUT_VDDO")
			(options
				(clearance outline)
				(anchor circle)
			)
			(primitives
				(gr_poly
					(pts
						(arc
							(start -0.1778 -0.2794)
							(mid -0.249642 -0.249642)
							(end -0.2794 -0.1778)
						)
						(arc
							(start -0.2794 0.1778)
							(mid -0.249642 0.249642)
							(end -0.1778 0.2794)
						)
						(arc
							(start 0.1778 0.2794)
							(mid 0.249642 0.249642)
							(end 0.2794 0.1778)
						)
						(arc
							(start 0.2794 -0.1778)
							(mid 0.249642 -0.249642)
							(end 0.1778 -0.2794)
						)
					)
					(width 0)
					(fill yes)
				)
			)
		)
		(pad "2" smd custom
			(at 0 0.4445 180)
			(size 0.1397 0.1397)
			(layers "F.Cu" "F.Mask" "F.Paste")
			(net "EJTAG_DINT")
			(options
				(clearance outline)
				(anchor circle)
			)
			(primitives
				(gr_poly
					(pts
						(arc
							(start -0.1778 -0.2794)
							(mid -0.249642 -0.249642)
							(end -0.2794 -0.1778)
						)
						(arc
							(start -0.2794 0.1778)
							(mid -0.249642 0.249642)
							(end -0.1778 0.2794)
						)
						(arc
							(start 0.1778 0.2794)
							(mid 0.249642 0.249642)
							(end 0.2794 0.1778)
						)
						(arc
							(start 0.2794 -0.1778)
							(mid 0.249642 -0.249642)
							(end 0.1778 -0.2794)
						)
					)
					(width 0)
					(fill yes)
				)
			)
		)
	)
	(footprint ""
		(layer "F.Cu")
		(at 155.882086 -33.421574 180)
		(property "Reference" "R669"
			(at 0 0 180)
			(layer "F.SilkS")
			(hide yes)
			(effects
				(font
					(size 1.27 1.27)
				)
			)
		)
		(property "Value" "0R2J-2-GP"
			(at 0.064008 -3.993896 180)
			(unlocked yes)
			(layer "F.Fab")
			(hide yes)
			(effects
				(font
					(size 1.016 1.016)
					(thickness 0.1524)
				)
			)
		)
		(property "Device Type" "R402H16"
			(at 0.064008 -5.517896 180)
			(unlocked yes)
			(layer "F.Fab")
			(hide yes)
			(effects
				(font
					(size 1.016 1.016)
					(thickness 0.1524)
				)
			)
		)
		(duplicate_pad_numbers_are_jumpers no)
		(fp_line
			(start 0.508 -0.9398)
			(end -0.508 -0.9398)
			(stroke
				(width 0.1524)
				(type default)
			)
			(layer "F.SilkS")
		)
		(fp_line
			(start -0.508 -0.9398)
			(end -0.508 0.9398)
			(stroke
				(width 0.1524)
				(type default)
			)
			(layer "F.SilkS")
		)
		(fp_rect
			(start -0.508 0.9398)
			(end 0.508 -0.9398)
			(stroke
				(width 0)
				(type default)
			)
			(fill no)
			(layer "F.CrtYd")
		)
		(fp_rect
			(start -0.508 0.9398)
			(end 0.508 -0.9398)
			(stroke
				(width 0)
				(type default)
			)
			(fill no)
			(layer "F.Fab")
		)
		(pad "1" smd custom
			(at 0 -0.4445 180)
			(size 0.1397 0.1397)
			(layers "F.Cu" "F.Mask" "F.Paste")
			(net "8644_USB_DN3")
			(options
				(clearance outline)
				(anchor circle)
			)
			(primitives
				(gr_poly
					(pts
						(arc
							(start -0.1778 -0.2794)
							(mid -0.249642 -0.249642)
							(end -0.2794 -0.1778)
						)
						(arc
							(start -0.2794 0.1778)
							(mid -0.249642 0.249642)
							(end -0.1778 0.2794)
						)
						(arc
							(start 0.1778 0.2794)
							(mid 0.249642 0.249642)
							(end 0.2794 0.1778)
						)
						(arc
							(start 0.2794 -0.1778)
							(mid 0.249642 -0.249642)
							(end 0.1778 -0.2794)
						)
					)
					(width 0)
					(fill yes)
				)
			)
		)
		(pad "2" smd custom
			(at 0 0.4445 180)
			(size 0.1397 0.1397)
			(layers "F.Cu" "F.Mask" "F.Paste")
			(net "P3V3_STBY")
			(options
				(clearance outline)
				(anchor circle)
			)
			(primitives
				(gr_poly
					(pts
						(arc
							(start -0.1778 -0.2794)
							(mid -0.249642 -0.249642)
							(end -0.2794 -0.1778)
						)
						(arc
							(start -0.2794 0.1778)
							(mid -0.249642 0.249642)
							(end -0.1778 0.2794)
						)
						(arc
							(start 0.1778 0.2794)
							(mid 0.249642 0.249642)
							(end 0.2794 0.1778)
						)
						(arc
							(start 0.2794 -0.1778)
							(mid 0.249642 -0.249642)
							(end 0.1778 -0.2794)
						)
					)
					(width 0)
					(fill yes)
				)
			)
		)
	)
	(footprint ""
		(layer "F.Cu")
		(at 219.813124 -190.601092)
		(property "Reference" "R7923"
			(at 0 0 0)
			(layer "F.SilkS")
			(hide yes)
			(effects
				(font
					(size 1.27 1.27)
				)
			)
		)
		(property "Value" "0R2J-2-GP"
			(at 0.064008 -3.993896 0)
			(unlocked yes)
			(layer "F.Fab")
			(hide yes)
			(effects
				(font
					(size 1.016 1.016)
					(thickness 0.1524)
				)
			)
		)
		(property "Device Type" "R402H16"
			(at 0.064008 -5.517896 0)
			(unlocked yes)
			(layer "F.Fab")
			(hide yes)
			(effects
				(font
					(size 1.016 1.016)
					(thickness 0.1524)
				)
			)
		)
		(duplicate_pad_numbers_are_jumpers no)
		(fp_line
			(start -0.508 -0.9398)
			(end -0.508 0.9398)
			(stroke
				(width 0.1524)
				(type default)
			)
			(layer "F.SilkS")
		)
		(fp_line
			(start 0.508 -0.9398)
			(end -0.508 -0.9398)
			(stroke
				(width 0.1524)
				(type default)
			)
			(layer "F.SilkS")
		)
		(fp_rect
			(start -0.508 0.9398)
			(end 0.508 -0.9398)
			(stroke
				(width 0)
				(type default)
			)
			(fill no)
			(layer "F.CrtYd")
		)
		(fp_rect
			(start -0.508 0.9398)
			(end 0.508 -0.9398)
			(stroke
				(width 0)
				(type default)
			)
			(fill no)
			(layer "F.Fab")
		)
		(pad "1" smd custom
			(at 0 -0.4445)
			(size 0.1397 0.1397)
			(layers "F.Cu" "F.Mask" "F.Paste")
			(net "SSD_PRSNT#3")
			(options
				(clearance outline)
				(anchor circle)
			)
			(primitives
				(gr_poly
					(pts
						(arc
							(start -0.1778 -0.2794)
							(mid -0.249642 -0.249642)
							(end -0.2794 -0.1778)
						)
						(arc
							(start -0.2794 0.1778)
							(mid -0.249642 0.249642)
							(end -0.1778 0.2794)
						)
						(arc
							(start 0.1778 0.2794)
							(mid 0.249642 0.249642)
							(end 0.2794 0.1778)
						)
						(arc
							(start 0.2794 -0.1778)
							(mid 0.249642 -0.249642)
							(end 0.1778 -0.2794)
						)
					)
					(width 0)
					(fill yes)
				)
			)
		)
		(pad "2" smd custom
			(at 0 0.4445)
			(size 0.1397 0.1397)
			(layers "F.Cu" "F.Mask" "F.Paste")
			(net "SSD_PRSNT#3_R")
			(options
				(clearance outline)
				(anchor circle)
			)
			(primitives
				(gr_poly
					(pts
						(arc
							(start -0.1778 -0.2794)
							(mid -0.249642 -0.249642)
							(end -0.2794 -0.1778)
						)
						(arc
							(start -0.2794 0.1778)
							(mid -0.249642 0.249642)
							(end -0.1778 0.2794)
						)
						(arc
							(start 0.1778 0.2794)
							(mid 0.249642 0.249642)
							(end 0.2794 0.1778)
						)
						(arc
							(start 0.2794 -0.1778)
							(mid 0.249642 -0.249642)
							(end 0.1778 -0.2794)
						)
					)
					(width 0)
					(fill yes)
				)
			)
		)
	)
	(footprint ""
		(layer "F.Cu")
		(at 164.8206 -206.883 -90)
		(property "Reference" "C4140"
			(at 0 0 270)
			(layer "F.SilkS")
			(hide yes)
			(effects
				(font
					(size 1.27 1.27)
				)
			)
		)
		(property "Value" "SCD1U25V3KX-GP"
			(at 0 -2.8194 270)
			(unlocked yes)
			(layer "F.Fab")
			(hide yes)
			(effects
				(font
					(size 1.016 1.016)
					(thickness 0.1524)
				)
			)
		)
		(property "Device Type" "C603H36"
			(at 0 -4.3434 270)
			(unlocked yes)
			(layer "F.Fab")
			(hide yes)
			(effects
				(font
					(size 1.016 1.016)
					(thickness 0.1524)
				)
			)
		)
		(duplicate_pad_numbers_are_jumpers no)
		(fp_line
			(start 0.508 0)
			(end -0.508 0)
			(stroke
				(width 0.2032)
				(type default)
			)
			(layer "F.SilkS")
		)
		(fp_rect
			(start -0.5842 1.3335)
			(end 0.5842 -1.3335)
			(stroke
				(width 0)
				(type default)
			)
			(fill no)
			(layer "F.CrtYd")
		)
		(fp_rect
			(start -0.5842 1.3335)
			(end 0.5842 -1.3335)
			(stroke
				(width 0)
				(type default)
			)
			(fill no)
			(layer "F.Fab")
		)
		(pad "1" smd custom
			(at 0 -0.762 270)
			(size 0.2159 0.2159)
			(layers "F.Cu" "F.Mask" "F.Paste")
			(net "GND")
			(options
				(clearance outline)
				(anchor circle)
			)
			(primitives
				(gr_poly
					(pts
						(arc
							(start -0.3302 -0.4318)
							(mid -0.402042 -0.402042)
							(end -0.4318 -0.3302)
						)
						(arc
							(start -0.4318 0.3302)
							(mid -0.402042 0.402042)
							(end -0.3302 0.4318)
						)
						(arc
							(start 0.3302 0.4318)
							(mid 0.402042 0.402042)
							(end 0.4318 0.3302)
						)
						(arc
							(start 0.4318 -0.3302)
							(mid 0.402042 -0.402042)
							(end 0.3302 -0.4318)
						)
					)
					(width 0)
					(fill yes)
				)
			)
		)
		(pad "2" smd custom
			(at 0 0.762 270)
			(size 0.2159 0.2159)
			(layers "F.Cu" "F.Mask" "F.Paste")
			(net "SSD_PWREN2_R")
			(options
				(clearance outline)
				(anchor circle)
			)
			(primitives
				(gr_poly
					(pts
						(arc
							(start -0.3302 -0.4318)
							(mid -0.402042 -0.402042)
							(end -0.4318 -0.3302)
						)
						(arc
							(start -0.4318 0.3302)
							(mid -0.402042 0.402042)
							(end -0.3302 0.4318)
						)
						(arc
							(start 0.3302 0.4318)
							(mid 0.402042 0.402042)
							(end 0.4318 0.3302)
						)
						(arc
							(start 0.4318 -0.3302)
							(mid 0.402042 -0.402042)
							(end 0.3302 -0.4318)
						)
					)
					(width 0)
					(fill yes)
				)
			)
		)
	)
	(footprint ""
		(layer "F.Cu")
		(at 13.7922 -186.6646)
		(property "Reference" "U2"
			(at 0 0 0)
			(layer "F.SilkS")
			(hide yes)
			(effects
				(font
					(size 1.27 1.27)
				)
			)
		)
		(property "Value" "ADM1278-2ACPZ-RL-1-GP"
			(at -4.7625 -7.4422 0)
			(unlocked yes)
			(layer "F.Fab")
			(hide yes)
			(effects
				(font
					(size 1.016 1.016)
					(thickness 0.1524)
				)
			)
		)
		(property "Device Type" "QFN32-G3D45-UH32"
			(at -4.7625 -8.9662 0)
			(unlocked yes)
			(layer "F.Fab")
			(hide yes)
			(effects
				(font
					(size 1.016 1.016)
					(thickness 0.1524)
				)
			)
		)
		(duplicate_pad_numbers_are_jumpers no)
		(fp_line
			(start -4.0513 -1.24968)
			(end -3.2893 -1.24968)
			(stroke
				(width 0.1524)
				(type default)
			)
			(layer "F.SilkS")
		)
		(fp_line
			(start -3.7973 1.24968)
			(end -3.2893 1.24968)
			(stroke
				(width 0.1524)
				(type default)
			)
			(layer "F.SilkS")
		)
		(fp_line
			(start -3.5179 -3.5179)
			(end -2.2479 -3.5179)
			(stroke
				(width 0.1524)
				(type default)
			)
			(layer "F.SilkS")
		)
		(fp_line
			(start -3.5179 -2.2479)
			(end -3.5179 -3.5179)
			(stroke
				(width 0.1524)
				(type default)
			)
			(layer "F.SilkS")
		)
		(fp_line
			(start -3.5179 2.2479)
			(end -3.5179 3.5179)
			(stroke
				(width 0.1524)
				(type default)
			)
			(layer "F.SilkS")
		)
		(fp_line
			(start -3.5179 3.5179)
			(end -2.2479 3.5179)
			(stroke
				(width 0.1524)
				(type default)
			)
			(layer "F.SilkS")
		)
		(fp_line
			(start -0.250698 -3.7973)
			(end -0.250698 -3.2893)
			(stroke
				(width 0.1524)
				(type default)
			)
			(layer "F.SilkS")
		)
		(fp_line
			(start -0.250698 4.0513)
			(end -0.250698 3.2893)
			(stroke
				(width 0.1524)
				(type default)
			)
			(layer "F.SilkS")
		)
		(fp_line
			(start 3.5179 2.2479)
			(end 3.5179 3.5179)
			(stroke
				(width 0.1524)
				(type default)
			)
			(layer "F.SilkS")
		)
		(fp_line
			(start 3.5179 3.5179)
			(end 2.2479 3.5179)
			(stroke
				(width 0.1524)
				(type default)
			)
			(layer "F.SilkS")
		)
		(fp_line
			(start 3.7973 1.749552)
			(end 3.2893 1.749552)
			(stroke
				(width 0.1524)
				(type default)
			)
			(layer "F.SilkS")
		)
		(fp_line
			(start 4.0513 -0.749808)
			(end 3.2893 -0.749808)
			(stroke
				(width 0.1524)
				(type default)
			)
			(layer "F.SilkS")
		)
		(fp_poly
			(pts
				(xy 2.2479 -3.5179) (xy 3.5179 -2.2479) (xy 3.5179 -3.5179)
			)
			(stroke
				(width 0)
				(type default)
			)
			(fill yes)
			(layer "F.SilkS")
		)
		(fp_rect
			(start -2.5019 2.5019)
			(end 2.5019 -2.5019)
			(stroke
				(width 0)
				(type default)
			)
			(fill no)
			(layer "F.CrtYd")
		)
		(fp_poly
			(pts
				(xy -3.5179 3.5179) (xy -3.5179 -3.5179) (xy 3.5179 -3.5179) (xy 3.5179 3.5179) (xy -2.49682 3.5179)
				(xy -2.49682 2.5019) (xy 2.5019 2.5019) (xy 2.5019 -2.5019) (xy -2.5019 -2.5019) (xy -2.5019 3.5179)
			)
			(stroke
				(width 0)
				(type default)
			)
			(fill no)
			(layer "F.CrtYd")
		)
		(fp_rect
			(start -3.5179 3.5179)
			(end 3.5179 -3.5179)
			(stroke
				(width 0)
				(type default)
			)
			(fill no)
			(layer "F.Fab")
		)
		(pad "1" smd rect
			(at 1.75006 -2.5527)
			(size 0.3048 0.9144)
			(layers "F.Cu" "F.Mask" "F.Paste")
			(net "MB0_PSET_R")
		)
		(pad "2" smd rect
			(at 1.249934 -2.4765)
			(size 0.3048 1.0668)
			(layers "F.Cu" "F.Mask" "F.Paste")
			(net "MB0_VCAP_R")
		)
		(pad "3" smd rect
			(at 0.750062 -2.4765)
			(size 0.3048 1.0668)
			(layers "F.Cu" "F.Mask" "F.Paste")
			(net "MB0_ISET_R")
		)
		(pad "4" smd rect
			(at 0.249936 -2.4765)
			(size 0.3048 1.0668)
			(layers "F.Cu" "F.Mask" "F.Paste")
			(net "MB0_ISTART_R")
		)
		(pad "5" smd rect
			(at -0.249936 -2.4765)
			(size 0.3048 1.0668)
			(layers "F.Cu" "F.Mask" "F.Paste")
			(net "MB0_TIME_R")
		)
		(pad "6" smd rect
			(at -0.750062 -2.4765)
			(size 0.3048 1.0668)
			(layers "F.Cu" "F.Mask" "F.Paste")
			(net "Net_2092")
		)
		(pad "7" smd rect
			(at -1.249934 -2.4765)
			(size 0.3048 1.0668)
			(layers "F.Cu" "F.Mask" "F.Paste")
			(net "MB0_CM_ADR1_R")
		)
		(pad "8" smd rect
			(at -1.75006 -2.5527)
			(size 0.3048 0.9144)
			(layers "F.Cu" "F.Mask" "F.Paste")
			(net "MB0_CM_ADR2_R")
		)
		(pad "9" smd rect
			(at -2.5527 -1.75006)
			(size 0.9144 0.3048)
			(layers "F.Cu" "F.Mask" "F.Paste")
			(net "MB0_SPISS_PD")
		)
		(pad "10" smd rect
			(at -2.4765 -1.249934)
			(size 1.0668 0.3048)
			(layers "F.Cu" "F.Mask" "F.Paste")
			(net "Net_2096")
		)
		(pad "11" smd rect
			(at -2.4765 -0.750062)
			(size 1.0668 0.3048)
			(layers "F.Cu" "F.Mask" "F.Paste")
			(net "Net_2095")
		)
		(pad "12" smd rect
			(at -2.4765 -0.249936)
			(size 1.0668 0.3048)
			(layers "F.Cu" "F.Mask" "F.Paste")
			(net "MB0_HS_ENABLE")
		)
		(pad "13" smd rect
			(at -2.4765 0.249936)
			(size 1.0668 0.3048)
			(layers "F.Cu" "F.Mask" "F.Paste")
			(net "Net_2094")
		)
		(pad "14" smd rect
			(at -2.4765 0.750062)
			(size 1.0668 0.3048)
			(layers "F.Cu" "F.Mask" "F.Paste")
			(net "Net_2093")
		)
		(pad "15" smd rect
			(at -2.4765 1.249934)
			(size 1.0668 0.3048)
			(layers "F.Cu" "F.Mask" "F.Paste")
			(net "HSW_SDA_2")
		)
		(pad "16" smd rect
			(at -2.5527 1.75006)
			(size 0.9144 0.3048)
			(layers "F.Cu" "F.Mask" "F.Paste")
			(net "HSW_SCL_2")
		)
		(pad "17" smd rect
			(at -1.75006 2.5527)
			(size 0.3048 0.9144)
			(layers "F.Cu" "F.Mask" "F.Paste")
			(net "MB0_RETRY_R")
		)
		(pad "18" smd rect
			(at -1.249934 2.4765)
			(size 0.3048 1.0668)
			(layers "F.Cu" "F.Mask" "F.Paste")
			(net "MB0_P12V_PWRGOOD")
		)
		(pad "19" smd rect
			(at -0.750062 2.4765)
			(size 0.3048 1.0668)
			(layers "F.Cu" "F.Mask" "F.Paste")
			(net "Net_2097")
		)
		(pad "20" smd rect
			(at -0.249936 2.4765)
			(size 0.3048 1.0668)
			(layers "F.Cu" "F.Mask" "F.Paste")
			(net "MB0_CM_VOUT_R")
		)
		(pad "21" smd rect
			(at 0.249936 2.4765)
			(size 0.3048 1.0668)
			(layers "F.Cu" "F.Mask" "F.Paste")
			(net "MB0_P12V_PWGIN_R")
		)
		(pad "22" smd rect
			(at 0.750062 2.4765)
			(size 0.3048 1.0668)
			(layers "F.Cu" "F.Mask" "F.Paste")
			(net "AGND_CURRENT_MON")
		)
		(pad "23" smd rect
			(at 1.249934 2.4765)
			(size 0.3048 1.0668)
			(layers "F.Cu" "F.Mask" "F.Paste")
			(net "GND")
		)
		(pad "24" smd rect
			(at 1.75006 2.5527)
			(size 0.3048 0.9144)
			(layers "F.Cu" "F.Mask" "F.Paste")
			(net "MB0_CM_GATE")
		)
		(pad "25" smd rect
			(at 2.5527 1.75006)
			(size 0.9144 0.3048)
			(layers "F.Cu" "F.Mask" "F.Paste")
			(net "MB0_TEMP")
		)
		(pad "26" smd rect
			(at 2.4765 1.249934)
			(size 1.0668 0.3048)
			(layers "F.Cu" "F.Mask" "F.Paste")
			(net "MB0_CM_SENSE_N")
		)
		(pad "27" smd rect
			(at 2.4765 0.750062)
			(size 1.0668 0.3048)
			(layers "F.Cu" "F.Mask" "F.Paste")
			(net "ADM1278_HS_N")
		)
		(pad "28" smd rect
			(at 2.4765 0.249936)
			(size 1.0668 0.3048)
			(layers "F.Cu" "F.Mask" "F.Paste")
			(net "ADM1278_HS_P")
		)
		(pad "29" smd rect
			(at 2.4765 -0.249936)
			(size 1.0668 0.3048)
			(layers "F.Cu" "F.Mask" "F.Paste")
			(net "MB0_CM_SENSE_P")
		)
		(pad "30" smd rect
			(at 2.4765 -0.750062)
			(size 1.0668 0.3048)
			(layers "F.Cu" "F.Mask" "F.Paste")
			(net "MB0_VCC")
		)
		(pad "31" smd rect
			(at 2.4765 -1.249934)
			(size 1.0668 0.3048)
			(layers "F.Cu" "F.Mask" "F.Paste")
			(net "MB0_CM_UV_R")
		)
		(pad "32" smd rect
			(at 2.5527 -1.75006)
			(size 0.9144 0.3048)
			(layers "F.Cu" "F.Mask" "F.Paste")
			(net "MB0_CM_OV_R")
		)
		(pad "33" smd rect
			(at 0 0)
			(size 3.4544 3.4544)
			(layers "F.Cu" "F.Mask" "F.Paste")
			(net "AGND_CURRENT_MON")
		)
	)
)
